(kicad_pcb
	(version 20241229)
	(generator "pcbnew")
	(generator_version "9.0")
	(general
		(thickness 1.61)
		(legacy_teardrops no)
	)
	(paper "A3")
	(title_block
		(title "SO-DIMM DDR5 Tester")
		(date "2025-11-26")
		(rev "1.3.0")
		(comment 9 "footprint 59 of 627 (U4), pads 355-425 of 676")
	)
	(layers
		(0 "F.Cu" signal)
		(4 "In1.Cu" power)
		(6 "In2.Cu" mixed)
		(8 "In3.Cu" power)
		(10 "In4.Cu" mixed)
		(12 "In5.Cu" power)
		(14 "In6.Cu" mixed)
		(16 "In7.Cu" power)
		(18 "In8.Cu" power)
		(20 "In9.Cu" mixed)
		(22 "In10.Cu" power)
		(2 "B.Cu" signal)
		(9 "F.Adhes" user "F.Adhesive")
		(11 "B.Adhes" user "B.Adhesive")
		(13 "F.Paste" user)
		(15 "B.Paste" user)
		(5 "F.SilkS" user "F.Silkscreen")
		(7 "B.SilkS" user "B.Silkscreen")
		(1 "F.Mask" user)
		(3 "B.Mask" user)
		(17 "Dwgs.User" user "User.Drawings")
		(19 "Cmts.User" user "User.Comments")
		(21 "Eco1.User" user "User.Eco1")
		(23 "Eco2.User" user "User.Eco2")
		(25 "Edge.Cuts" user)
		(27 "Margin" user)
		(31 "F.CrtYd" user "F.Courtyard")
		(29 "B.CrtYd" user "B.Courtyard")
		(35 "F.Fab" user)
		(33 "B.Fab" user)
	)
	(footprint "antmicro-footprints:BGA-676_27x27mm_Layout26x26_P1x1mm_FFG676"
		(layer "F.Cu")
		(at 138.875501 174.801 180)
		(descr "FPGA XC7K160TFBG676")
		(tags "FPGA XC7K160TFBG676")
		(property "Reference" "U4"
			(at -12.224499 14.051 180)
			(layer "F.SilkS")
			(effects
				(font
					(size 0.7 0.7)
					(thickness 0.15)
				)
				(justify left bottom)
			)
		)
		(property "Value" "XC7K160T-FFG676"
			(at 0 15.5 180)
			(layer "F.Fab")
			(effects
				(font
					(size 0.7 0.7)
					(thickness 0.15)
				)
				(justify left bottom)
			)
		)
		(property "Datasheet" "https://docs.xilinx.com/v/u/en-US/ds180_7Series_Overview"
			(at 0 0 180)
			(layer "F.Fab")
			(hide yes)
			(effects
				(font
					(size 1.27 1.27)
					(thickness 0.15)
				)
			)
		)
		(property "Author" "Antmicro"
			(at 277.751002 349.602 0)
			(layer "F.Fab")
			(hide yes)
			(effects
				(font
					(size 1 1)
					(thickness 0.15)
				)
			)
		)
		(property "License" "Apache-2.0"
			(at 277.751002 349.602 0)
			(layer "F.Fab")
			(hide yes)
			(effects
				(font
					(size 1 1)
					(thickness 0.15)
				)
			)
		)
		(property "MPN" "XC7K160T-FFG676"
			(at 277.751002 349.602 0)
			(layer "F.Fab")
			(hide yes)
			(effects
				(font
					(size 1 1)
					(thickness 0.15)
				)
			)
		)
		(property "Manufacturer" "AMD-Xilinx"
			(at 277.751002 349.602 0)
			(layer "F.Fab")
			(hide yes)
			(effects
				(font
					(size 1 1)
					(thickness 0.15)
				)
			)
		)
		(sheetname "/FPGA Config/")
		(sheetfile "fpga-config.kicad_sch")
		(attr smd)
		(pad "H17" smd circle
			(at 3.499 -5.5 180)
			(size 0.5 0.5)
			(layers "F.Cu" "F.Mask" "F.Paste")
			(net 467 "unconnected-(U4D-IO_L14P_T2_SRCC_15-PadH17)")
			(pinfunction "IO_L14P_T2_SRCC_15")
			(pintype "bidirectional+no_connect")
			(die_length 11.166)
		)
		(pad "H18" smd circle
			(at 4.499 -5.5 180)
			(size 0.5 0.5)
			(layers "F.Cu" "F.Mask" "F.Paste")
			(net 468 "unconnected-(U4D-IO_L14N_T2_SRCC_15-PadH18)")
			(pinfunction "IO_L14N_T2_SRCC_15")
			(pintype "bidirectional+no_connect")
			(die_length 11.108)
		)
		(pad "H19" smd circle
			(at 5.499 -5.5 180)
			(size 0.5 0.5)
			(layers "F.Cu" "F.Mask" "F.Paste")
			(net 469 "unconnected-(U4D-IO_L18P_T2_A24_15-PadH19)")
			(pinfunction "IO_L18P_T2_A24_15")
			(pintype "bidirectional+no_connect")
			(die_length 11.791)
		)
		(pad "H20" smd circle
			(at 6.499 -5.5 180)
			(size 0.5 0.5)
			(layers "F.Cu" "F.Mask" "F.Paste")
			(net 377 "Net-(R97-Pad2)")
			(pinfunction "VCCO_15")
			(pintype "passive")
		)
		(pad "H21" smd circle
			(at 7.499 -5.5 180)
			(size 0.5 0.5)
			(layers "F.Cu" "F.Mask" "F.Paste")
			(net 272 "FAN_PWM")
			(pinfunction "IO_L19P_T3_A10_D26_14")
			(pintype "bidirectional")
			(die_length 18.685)
		)
		(pad "H22" smd circle
			(at 8.499 -5.5 180)
			(size 0.5 0.5)
			(layers "F.Cu" "F.Mask" "F.Paste")
			(net 689 "/FPGA bank 14/FPGA_PWR.SCL")
			(pinfunction "IO_L21N_T3_DQS_A06_D22_14")
			(pintype "bidirectional")
			(die_length 20.841)
		)
		(pad "H23" smd circle
			(at 9.499 -5.5 180)
			(size 0.5 0.5)
			(layers "F.Cu" "F.Mask" "F.Paste")
			(net 470 "unconnected-(U4C-IO_L20P_T3_A08_D24_14-PadH23)")
			(pinfunction "IO_L20P_T3_A08_D24_14")
			(pintype "bidirectional+no_connect")
			(die_length 18.73)
		)
		(pad "H24" smd circle
			(at 10.499 -5.5 180)
			(size 0.5 0.5)
			(layers "F.Cu" "F.Mask" "F.Paste")
			(net 471 "unconnected-(U4C-IO_L20N_T3_A07_D23_14-PadH24)")
			(pinfunction "IO_L20N_T3_A07_D23_14")
			(pintype "bidirectional+no_connect")
			(die_length 17.912)
		)
		(pad "H25" smd circle
			(at 11.499 -5.5 180)
			(size 0.5 0.5)
			(layers "F.Cu" "F.Mask" "F.Paste")
			(net 1 "GND")
			(pinfunction "GND")
			(pintype "passive")
		)
		(pad "H26" smd circle
			(at 12.499 -5.5 180)
			(size 0.5 0.5)
			(layers "F.Cu" "F.Mask" "F.Paste")
			(net 472 "unconnected-(U4C-IO_L18N_T2_A11_D27_14-PadH26)")
			(pinfunction "IO_L18N_T2_A11_D27_14")
			(pintype "bidirectional+no_connect")
			(die_length 19.909)
		)
		(pad "J1" smd circle
			(at -12.5 -4.5 180)
			(size 0.5 0.5)
			(layers "F.Cu" "F.Mask" "F.Paste")
			(net 1 "GND")
			(pinfunction "GND")
			(pintype "passive")
		)
		(pad "J2" smd circle
			(at -11.5 -4.5 180)
			(size 0.5 0.5)
			(layers "F.Cu" "F.Mask" "F.Paste")
			(net 1 "GND")
			(pinfunction "GND")
			(pintype "passive")
		)
		(pad "J3" smd circle
			(at -10.5 -4.5 180)
			(size 0.5 0.5)
			(layers "F.Cu" "F.Mask" "F.Paste")
			(net 473 "unconnected-(U4I-MGTXRXN3_115-PadJ3)")
			(pinfunction "MGTXRXN3_115")
			(pintype "bidirectional+no_connect")
			(die_length 11.806)
		)
		(pad "J4" smd circle
			(at -9.5 -4.5 180)
			(size 0.5 0.5)
			(layers "F.Cu" "F.Mask" "F.Paste")
			(net 474 "unconnected-(U4I-MGTXRXP3_115-PadJ4)")
			(pinfunction "MGTXRXP3_115")
			(pintype "bidirectional+no_connect")
			(die_length 11.935)
		)
		(pad "J5" smd circle
			(at -8.5 -4.5 180)
			(size 0.5 0.5)
			(layers "F.Cu" "F.Mask" "F.Paste")
			(net 1 "GND")
			(pinfunction "GND")
			(pintype "passive")
		)
		(pad "J6" smd circle
			(at -7.5 -4.5 180)
			(size 0.5 0.5)
			(layers "F.Cu" "F.Mask" "F.Paste")
			(net 187 "+1V0_MGTAVCC")
			(pinfunction "MGTAVCC")
			(pintype "passive")
		)
		(pad "J7" smd circle
			(at -6.5 -4.5 180)
			(size 0.5 0.5)
			(layers "F.Cu" "F.Mask" "F.Paste")
			(net 613 "/FPGA Config/DONE")
			(pinfunction "DONE_0")
			(pintype "bidirectional")
			(die_length 33.726)
		)
		(pad "J8" smd circle
			(at -5.5 -4.5 180)
			(size 0.5 0.5)
			(layers "F.Cu" "F.Mask" "F.Paste")
			(net 475 "unconnected-(U4E-IO_0_16-PadJ8)")
			(pinfunction "IO_0_16")
			(pintype "bidirectional+no_connect")
			(die_length 17.143)
		)
		(pad "J9" smd circle
			(at -4.5 -4.5 180)
			(size 0.5 0.5)
			(layers "F.Cu" "F.Mask" "F.Paste")
			(net 227 "+1V0")
			(pinfunction "VCCINT")
			(pintype "power_in")
		)
		(pad "J10" smd circle
			(at -3.5 -4.5 180)
			(size 0.5 0.5)
			(layers "F.Cu" "F.Mask" "F.Paste")
			(net 476 "unconnected-(U4E-IO_L4N_T0_16-PadJ10)")
			(pinfunction "IO_L4N_T0_16")
			(pintype "bidirectional+no_connect")
			(die_length 16.988)
		)
		(pad "J11" smd circle
			(at -2.5 -4.5 180)
			(size 0.5 0.5)
			(layers "F.Cu" "F.Mask" "F.Paste")
			(net 477 "unconnected-(U4E-IO_L4P_T0_16-PadJ11)")
			(pinfunction "IO_L4P_T0_16")
			(pintype "bidirectional+no_connect")
			(die_length 16.441)
		)
		(pad "J12" smd circle
			(at -1.5 -4.5 180)
			(size 0.5 0.5)
			(layers "F.Cu" "F.Mask" "F.Paste")
			(net 1 "GND")
			(pinfunction "GND")
			(pintype "passive")
		)
		(pad "J13" smd circle
			(at -0.5 -4.5 180)
			(size 0.5 0.5)
			(layers "F.Cu" "F.Mask" "F.Paste")
			(net 478 "unconnected-(U4E-IO_L3P_T0_DQS_16-PadJ13)")
			(pinfunction "IO_L3P_T0_DQS_16")
			(pintype "bidirectional+no_connect")
			(die_length 12.775)
		)
		(pad "J14" smd circle
			(at 0.499 -4.5 180)
			(size 0.5 0.5)
			(layers "F.Cu" "F.Mask" "F.Paste")
			(net 479 "unconnected-(U4E-IO_25_16-PadJ14)")
			(pinfunction "IO_25_16")
			(pintype "bidirectional+no_connect")
			(die_length 13.82)
		)
		(pad "J15" smd circle
			(at 1.499 -4.5 180)
			(size 0.5 0.5)
			(layers "F.Cu" "F.Mask" "F.Paste")
			(net 480 "unconnected-(U4D-IO_L9P_T1_DQS_AD11P_15-PadJ15)")
			(pinfunction "IO_L9P_T1_DQS_AD11P_15")
			(pintype "bidirectional+no_connect")
			(die_length 15.384)
		)
		(pad "J16" smd circle
			(at 2.499 -4.5 180)
			(size 0.5 0.5)
			(layers "F.Cu" "F.Mask" "F.Paste")
			(net 481 "unconnected-(U4D-IO_L9N_T1_DQS_AD11N_15-PadJ16)")
			(pinfunction "IO_L9N_T1_DQS_AD11N_15")
			(pintype "bidirectional+no_connect")
			(die_length 14.742)
		)
		(pad "J17" smd circle
			(at 3.499 -4.5 180)
			(size 0.5 0.5)
			(layers "F.Cu" "F.Mask" "F.Paste")
			(net 377 "Net-(R97-Pad2)")
			(pinfunction "VCCO_15")
			(pintype "passive")
		)
		(pad "J18" smd circle
			(at 4.499 -4.5 180)
			(size 0.5 0.5)
			(layers "F.Cu" "F.Mask" "F.Paste")
			(net 482 "unconnected-(U4D-IO_L20P_T3_A20_15-PadJ18)")
			(pinfunction "IO_L20P_T3_A20_15")
			(pintype "bidirectional+no_connect")
			(die_length 11.906)
		)
		(pad "J19" smd circle
			(at 5.499 -4.5 180)
			(size 0.5 0.5)
			(layers "F.Cu" "F.Mask" "F.Paste")
			(net 483 "unconnected-(U4D-IO_L20N_T3_A19_15-PadJ19)")
			(pinfunction "IO_L20N_T3_A19_15")
			(pintype "bidirectional+no_connect")
			(die_length 11.025)
		)
		(pad "J20" smd circle
			(at 6.499 -4.5 180)
			(size 0.5 0.5)
			(layers "F.Cu" "F.Mask" "F.Paste")
			(net 484 "unconnected-(U4D-IO_L19N_T3_A21_VREF_15-PadJ20)")
			(pinfunction "IO_L19N_T3_A21_VREF_15")
			(pintype "bidirectional+no_connect")
			(die_length 9.831)
		)
		(pad "J21" smd circle
			(at 7.499 -4.5 180)
			(size 0.5 0.5)
			(layers "F.Cu" "F.Mask" "F.Paste")
			(net 485 "unconnected-(U4C-IO_L21P_T3_DQS_14-PadJ21)")
			(pinfunction "IO_L21P_T3_DQS_14")
			(pintype "bidirectional+no_connect")
			(die_length 21.288)
		)
		(pad "J22" smd circle
			(at 8.499 -4.5 180)
			(size 0.5 0.5)
			(layers "F.Cu" "F.Mask" "F.Paste")
			(net 1 "GND")
			(pinfunction "GND")
			(pintype "passive")
		)
		(pad "J23" smd circle
			(at 9.499 -4.5 180)
			(size 0.5 0.5)
			(layers "F.Cu" "F.Mask" "F.Paste")
			(net 486 "unconnected-(U4C-IO_L24N_T3_A00_D16_14-PadJ23)")
			(pinfunction "IO_L24N_T3_A00_D16_14")
			(pintype "bidirectional+no_connect")
			(die_length 18.062)
		)
		(pad "J24" smd circle
			(at 10.499 -4.5 180)
			(size 0.5 0.5)
			(layers "F.Cu" "F.Mask" "F.Paste")
			(net 487 "unconnected-(U4C-IO_L22P_T3_A05_D21_14-PadJ24)")
			(pinfunction "IO_L22P_T3_A05_D21_14")
			(pintype "bidirectional+no_connect")
			(die_length 17.661)
		)
		(pad "J25" smd circle
			(at 11.499 -4.5 180)
			(size 0.5 0.5)
			(layers "F.Cu" "F.Mask" "F.Paste")
			(net 488 "unconnected-(U4C-IO_L22N_T3_A04_D20_14-PadJ25)")
			(pinfunction "IO_L22N_T3_A04_D20_14")
			(pintype "bidirectional+no_connect")
			(die_length 17.645)
		)
		(pad "J26" smd circle
			(at 12.499 -4.5 180)
			(size 0.5 0.5)
			(layers "F.Cu" "F.Mask" "F.Paste")
			(net 489 "unconnected-(U4C-IO_L18P_T2_A12_D28_14-PadJ26)")
			(pinfunction "IO_L18P_T2_A12_D28_14")
			(pintype "bidirectional+no_connect")
			(die_length 21.026)
		)
		(pad "K1" smd circle
			(at -12.5 -3.5 180)
			(size 0.5 0.5)
			(layers "F.Cu" "F.Mask" "F.Paste")
			(net 490 "unconnected-(U4I-MGTXTXN2_115-PadK1)")
			(pinfunction "MGTXTXN2_115")
			(pintype "bidirectional+no_connect")
			(die_length 13.554)
		)
		(pad "K2" smd circle
			(at -11.5 -3.5 180)
			(size 0.5 0.5)
			(layers "F.Cu" "F.Mask" "F.Paste")
			(net 491 "unconnected-(U4I-MGTXTXP2_115-PadK2)")
			(pinfunction "MGTXTXP2_115")
			(pintype "bidirectional+no_connect")
			(die_length 13.554)
		)
		(pad "K3" smd circle
			(at -10.5 -3.5 180)
			(size 0.5 0.5)
			(layers "F.Cu" "F.Mask" "F.Paste")
			(net 1 "GND")
			(pinfunction "GND")
			(pintype "passive")
		)
		(pad "K4" smd circle
			(at -9.5 -3.5 180)
			(size 0.5 0.5)
			(layers "F.Cu" "F.Mask" "F.Paste")
			(net 1 "GND")
			(pinfunction "GND")
			(pintype "passive")
		)
		(pad "K5" smd circle
			(at -8.5 -3.5 180)
			(size 0.5 0.5)
			(layers "F.Cu" "F.Mask" "F.Paste")
			(net 492 "unconnected-(U4I-MGTREFCLK1N_115-PadK5)")
			(pinfunction "MGTREFCLK1N_115")
			(pintype "bidirectional+no_connect")
			(die_length 11.876)
		)
		(pad "K6" smd circle
			(at -7.5 -3.5 180)
			(size 0.5 0.5)
			(layers "F.Cu" "F.Mask" "F.Paste")
			(net 493 "unconnected-(U4I-MGTREFCLK1P_115-PadK6)")
			(pinfunction "MGTREFCLK1P_115")
			(pintype "bidirectional+no_connect")
			(die_length 11.561)
		)
		(pad "K7" smd circle
			(at -6.5 -3.5 180)
			(size 0.5 0.5)
			(layers "F.Cu" "F.Mask" "F.Paste")
			(net 1 "GND")
			(pinfunction "GND")
			(pintype "passive")
		)
		(pad "K8" smd circle
			(at -5.5 -3.5 180)
			(size 0.5 0.5)
			(layers "F.Cu" "F.Mask" "F.Paste")
			(net 227 "+1V0")
			(pinfunction "VCCINT")
			(pintype "passive")
		)
		(pad "K9" smd circle
			(at -4.5 -3.5 180)
			(size 0.5 0.5)
			(layers "F.Cu" "F.Mask" "F.Paste")
			(net 1 "GND")
			(pinfunction "GND")
			(pintype "passive")
		)
		(pad "K10" smd circle
			(at -3.5 -3.5 180)
			(size 0.5 0.5)
			(layers "F.Cu" "F.Mask" "F.Paste")
			(net 227 "+1V0")
			(pinfunction "VCCINT")
			(pintype "passive")
		)
		(pad "K11" smd circle
			(at -2.5 -3.5 180)
			(size 0.5 0.5)
			(layers "F.Cu" "F.Mask" "F.Paste")
			(net 1 "GND")
			(pinfunction "GND")
			(pintype "passive")
		)
		(pad "K12" smd circle
			(at -1.5 -3.5 180)
			(size 0.5 0.5)
			(layers "F.Cu" "F.Mask" "F.Paste")
			(net 227 "+1V0")
			(pinfunction "VCCINT")
			(pintype "passive")
		)
		(pad "K13" smd circle
			(at -0.5 -3.5 180)
			(size 0.5 0.5)
			(layers "F.Cu" "F.Mask" "F.Paste")
			(net 1 "GND")
			(pinfunction "GND")
			(pintype "passive")
		)
		(pad "K14" smd circle
			(at 0.499 -3.5 180)
			(size 0.5 0.5)
			(layers "F.Cu" "F.Mask" "F.Paste")
			(net 227 "+1V0")
			(pinfunction "VCCINT")
			(pintype "passive")
		)
		(pad "K15" smd circle
			(at 1.499 -3.5 180)
			(size 0.5 0.5)
			(layers "F.Cu" "F.Mask" "F.Paste")
			(net 494 "unconnected-(U4D-IO_0_15-PadK15)")
			(pinfunction "IO_0_15")
			(pintype "bidirectional+no_connect")
			(die_length 6.731)
		)
		(pad "K16" smd circle
			(at 2.499 -3.5 180)
			(size 0.5 0.5)
			(layers "F.Cu" "F.Mask" "F.Paste")
			(net 495 "unconnected-(U4D-IO_L22P_T3_A17_15-PadK16)")
			(pinfunction "IO_L22P_T3_A17_15")
			(pintype "bidirectional+no_connect")
			(die_length 6.898)
		)
		(pad "K17" smd circle
			(at 3.499 -3.5 180)
			(size 0.5 0.5)
			(layers "F.Cu" "F.Mask" "F.Paste")
			(net 496 "unconnected-(U4D-IO_L22N_T3_A16_15-PadK17)")
			(pinfunction "IO_L22N_T3_A16_15")
			(pintype "bidirectional+no_connect")
			(die_length 7.2)
		)
		(pad "K18" smd circle
			(at 4.499 -3.5 180)
			(size 0.5 0.5)
			(layers "F.Cu" "F.Mask" "F.Paste")
			(net 497 "unconnected-(U4D-IO_L24N_T3_RS0_15-PadK18)")
			(pinfunction "IO_L24N_T3_RS0_15")
			(pintype "bidirectional+no_connect")
			(die_length 7.112)
		)
		(pad "K19" smd circle
			(at 5.499 -3.5 180)
			(size 0.5 0.5)
			(layers "F.Cu" "F.Mask" "F.Paste")
			(net 1 "GND")
			(pinfunction "GND")
			(pintype "passive")
		)
		(pad "K20" smd circle
			(at 6.499 -3.5 180)
			(size 0.5 0.5)
			(layers "F.Cu" "F.Mask" "F.Paste")
			(net 498 "unconnected-(U4D-IO_L19P_T3_A22_15-PadK20)")
			(pinfunction "IO_L19P_T3_A22_15")
			(pintype "bidirectional+no_connect")
			(die_length 8.708)
		)
		(pad "K21" smd circle
			(at 7.499 -3.5 180)
			(size 0.5 0.5)
			(layers "F.Cu" "F.Mask" "F.Paste")
			(net 499 "unconnected-(U4C-IO_0_14-PadK21)")
			(pinfunction "IO_0_14")
			(pintype "bidirectional+no_connect")
			(die_length 10.072)
		)
		(pad "K22" smd circle
			(at 8.499 -3.5 180)
			(size 0.5 0.5)
			(layers "F.Cu" "F.Mask" "F.Paste")
			(net 500 "unconnected-(U4C-IO_L23N_T3_A02_D18_14-PadK22)")
			(pinfunction "IO_L23N_T3_A02_D18_14")
			(pintype "bidirectional+no_connect")
			(die_length 16.883)
		)
		(pad "K23" smd circle
			(at 9.499 -3.5 180)
			(size 0.5 0.5)
			(layers "F.Cu" "F.Mask" "F.Paste")
			(net 501 "unconnected-(U4C-IO_L24P_T3_A01_D17_14-PadK23)")
			(pinfunction "IO_L24P_T3_A01_D17_14")
			(pintype "bidirectional+no_connect")
			(die_length 17.632)
		)
		(pad "K24" smd circle
			(at 10.499 -3.5 180)
			(size 0.5 0.5)
			(layers "F.Cu" "F.Mask" "F.Paste")
			(net 376 "Net-(R96-Pad2)")
			(pinfunction "VCCO_13")
			(pintype "power_in")
		)
		(pad "K25" smd circle
			(at 11.499 -3.5 180)
			(size 0.5 0.5)
			(layers "F.Cu" "F.Mask" "F.Paste")
			(net 502 "unconnected-(U4B-IO_L1P_T0_13-PadK25)")
			(pinfunction "IO_L1P_T0_13")
			(pintype "bidirectional+no_connect")
			(die_length 16.886)
		)
		(pad "K26" smd circle
			(at 12.499 -3.5 180)
			(size 0.5 0.5)
			(layers "F.Cu" "F.Mask" "F.Paste")
			(net 503 "unconnected-(U4B-IO_L1N_T0_13-PadK26)")
			(pinfunction "IO_L1N_T0_13")
			(pintype "bidirectional+no_connect")
			(die_length 17.592)
		)
		(pad "L1" smd circle
			(at -12.5 -2.5 180)
			(size 0.5 0.5)
			(layers "F.Cu" "F.Mask" "F.Paste")
			(net 1 "GND")
			(pinfunction "GND")
			(pintype "passive")
		)
		(pad "L2" smd circle
			(at -11.5 -2.5 180)
			(size 0.5 0.5)
			(layers "F.Cu" "F.Mask" "F.Paste")
			(net 226 "+1V2_MGTAVTT")
			(pinfunction "MGTAVTT")
			(pintype "passive")
		)
		(pad "L3" smd circle
			(at -10.5 -2.5 180)
			(size 0.5 0.5)
			(layers "F.Cu" "F.Mask" "F.Paste")
			(net 504 "unconnected-(U4I-MGTXRXN2_115-PadL3)")
			(pinfunction "MGTXRXN2_115")
			(pintype "bidirectional+no_connect")
			(die_length 11.935)
		)
		(pad "L4" smd circle
			(at -9.5 -2.5 180)
			(size 0.5 0.5)
			(layers "F.Cu" "F.Mask" "F.Paste")
			(net 505 "unconnected-(U4I-MGTXRXP2_115-PadL4)")
			(pinfunction "MGTXRXP2_115")
			(pintype "bidirectional+no_connect")
			(die_length 12.06)
		)
		(pad "L5" smd circle
			(at -8.5 -2.5 180)
			(size 0.5 0.5)
			(layers "F.Cu" "F.Mask" "F.Paste")
			(net 1 "GND")
			(pinfunction "GND")
			(pintype "passive")
		)
		(pad "L6" smd circle
			(at -7.5 -2.5 180)
			(size 0.5 0.5)
			(layers "F.Cu" "F.Mask" "F.Paste")
			(net 187 "+1V0_MGTAVCC")
			(pinfunction "MGTAVCC")
			(pintype "passive")
		)
		(pad "L7" smd circle
			(at -6.5 -2.5 180)
			(size 0.5 0.5)
			(layers "F.Cu" "F.Mask" "F.Paste")
			(net 200 "+3V3")
			(pinfunction "VCCO_0")
			(pintype "power_in")
		)
		(pad "L8" smd circle
			(at -5.5 -2.5 180)
			(size 0.5 0.5)
			(layers "F.Cu" "F.Mask" "F.Paste")
			(net 46 "/Debug FTDI/JTAG.TCK")
			(pinfunction "TCK_0")
			(pintype "bidirectional")
			(die_length 14.628)
		)
		(pad "L9" smd circle
			(at -4.5 -2.5 180)
			(size 0.5 0.5)
			(layers "F.Cu" "F.Mask" "F.Paste")
			(net 227 "+1V0")
			(pinfunction "VCCINT")
			(pintype "passive")
		)
	)
)
